-- pcdb file, Rev:1.0 written by Concept-HDL 13.60-s020 23-Feb-2001 on Mon Jan 06 13:12:19 2003
#ISCELL
  mstr_standard drawing *
  *
#ISCELL
  mstr_standard synonym *
  page1_4p
